# T6G (Grand Teton) — schematic netlist excerpt (pin names and nets, part order shuffled) for the footprints in the layout excerpt that follows; sources: Cadence DE-HDL packaged netlist, KiCad conversion of 04192023_DAF0TMB3IC0_F0TG_MB_C_brd_V02_OCP.brd

R8088  Q_RES  10K 1% EMPTY  pkg 0402LF  page 98 : A = P3V3_AUX ; B = PWRGD_CHAF_CPU1_R1
PR2149  Q_RES  0 5% CHIP  pkg 0402LF  page 262 : A = HSC_VDD_R ; B = HSC_VDD

(kicad_pcb
	(version 20260206)
	(generator "pcbnew")
	(generator_version "10.0")
	(general
		(thickness 1.6)
		(legacy_teardrops no)
	)
	(paper "A4")
	(title_block
		(title "04192023_DAF0TMB3IC0_F0TG_MB_C_brd_V02_OCP.brd")
		(comment 1 "Grand Teton / footprints 3276-3277 of 8354")
	)
	(layers
		(0 "F.Cu" signal "TOP")
		(4 "In1.Cu" signal "GND")
		(6 "In2.Cu" signal "IN1")
		(8 "In3.Cu" signal "GND1")
		(10 "In4.Cu" signal "IN2")
		(12 "In5.Cu" signal "GND2")
		(14 "In6.Cu" signal "IN3")
		(16 "In7.Cu" signal "GND3")
		(18 "In8.Cu" signal "VCC")
		(20 "In9.Cu" signal "VCC1")
		(22 "In10.Cu" signal "GND4")
		(24 "In11.Cu" signal "IN4")
		(26 "In12.Cu" signal "GND5")
		(28 "In13.Cu" signal "IN5")
		(30 "In14.Cu" signal "GND6")
		(32 "In15.Cu" signal "IN6")
		(34 "In16.Cu" signal "GND7")
		(2 "B.Cu" signal "BOTTOM")
		(9 "F.Adhes" user "F.Adhesive")
		(11 "B.Adhes" user "B.Adhesive")
		(13 "F.Paste" user "Package Geometry/Pastemask Top")
		(15 "B.Paste" user "Package Geometry/Pastemask Bottom")
		(5 "F.SilkS" user "Ref Des/Silkscreen Top")
		(7 "B.SilkS" user "Ref Des/Silkscreen Bottom")
		(1 "F.Mask" user "Board Geometry/Soldermask Top")
		(3 "B.Mask" user "Board Geometry/Soldermask Bottom")
		(17 "Dwgs.User" user "User.Drawings")
		(19 "Cmts.User" user "User.Comments")
		(21 "Eco1.User" user "User.Eco1")
		(23 "Eco2.User" user "User.Eco2")
		(25 "Edge.Cuts" user "Board Geometry/Outline")
		(27 "Margin" user)
		(31 "F.CrtYd" user "Package Geometry/Place Bound Top")
		(29 "B.CrtYd" user "Package Geometry/Place Bound Bottom")
		(35 "F.Fab" user "Ref Des/Assembly Top")
		(33 "B.Fab" user "Ref Des/Assembly Bottom")
	)
	(footprint ""
		(layer "F.Cu")
		(at 178.71694 -403.484842 180)
		(property "Reference" "PR2149"
			(at 0 0 180)
			(layer "F.SilkS")
			(hide yes)
			(effects
				(font
					(size 1.27 1.27)
				)
			)
		)
		(property "Value" ""
			(at 0 0 180)
			(layer "F.Fab")
			(effects
				(font
					(size 1.27 1.27)
				)
			)
		)
		(duplicate_pad_numbers_are_jumpers no)
		(fp_line
			(start 0.7874 0.4064)
			(end -0.7874 0.4064)
			(stroke
				(width 0.1524)
				(type default)
			)
			(layer "F.SilkS")
		)
		(fp_line
			(start 0.7874 -0.4064)
			(end 0.7874 0.4064)
			(stroke
				(width 0.1524)
				(type default)
			)
			(layer "F.SilkS")
		)
		(fp_line
			(start -0.7874 0.4064)
			(end -0.7874 -0.4064)
			(stroke
				(width 0.1524)
				(type default)
			)
			(layer "F.SilkS")
		)
		(fp_line
			(start -0.7874 -0.4064)
			(end 0.7874 -0.4064)
			(stroke
				(width 0.1524)
				(type default)
			)
			(layer "F.SilkS")
		)
		(fp_line
			(start 0.67945 0.3048)
			(end 0.120396 0.3048)
			(stroke
				(width 0.1)
				(type default)
			)
			(layer "F.Fab")
		)
		(fp_line
			(start 0.67945 -0.3048)
			(end 0.67945 0.3048)
			(stroke
				(width 0.1)
				(type default)
			)
			(layer "F.Fab")
		)
		(fp_line
			(start 0.12065 -0.2794)
			(end 0.12065 -0.3048)
			(stroke
				(width 0.1)
				(type default)
			)
			(layer "F.Fab")
		)
		(fp_line
			(start 0.12065 -0.3048)
			(end 0.67945 -0.3048)
			(stroke
				(width 0.1)
				(type default)
			)
			(layer "F.Fab")
		)
		(fp_line
			(start 0.120396 0.3048)
			(end 0.120396 0.2794)
			(stroke
				(width 0.1)
				(type default)
			)
			(layer "F.Fab")
		)
		(fp_line
			(start 0.120396 0.2794)
			(end -0.12065 0.2794)
			(stroke
				(width 0.1)
				(type default)
			)
			(layer "F.Fab")
		)
		(fp_line
			(start -0.12065 0.3048)
			(end -0.67945 0.3048)
			(stroke
				(width 0.1)
				(type default)
			)
			(layer "F.Fab")
		)
		(fp_line
			(start -0.12065 0.2794)
			(end -0.12065 0.3048)
			(stroke
				(width 0.1)
				(type default)
			)
			(layer "F.Fab")
		)
		(fp_line
			(start -0.12065 -0.2794)
			(end 0.12065 -0.2794)
			(stroke
				(width 0.1)
				(type default)
			)
			(layer "F.Fab")
		)
		(fp_line
			(start -0.12065 -0.305054)
			(end -0.12065 -0.2794)
			(stroke
				(width 0.1)
				(type default)
			)
			(layer "F.Fab")
		)
		(fp_line
			(start -0.67945 0.3048)
			(end -0.67945 -0.305054)
			(stroke
				(width 0.1)
				(type default)
			)
			(layer "F.Fab")
		)
		(fp_line
			(start -0.67945 -0.305054)
			(end -0.12065 -0.305054)
			(stroke
				(width 0.1)
				(type default)
			)
			(layer "F.Fab")
		)
		(pad "1" smd circle
			(at -0.40005 0 180)
			(size 0 0)
			(layers "F.Cu" "F.Mask" "F.Paste")
			(net "HSC_VDD_R")
		)
		(pad "2" smd circle
			(at 0.40005 0 180)
			(size 0 0)
			(layers "F.Cu" "F.Mask" "F.Paste")
			(net "HSC_VDD")
		)
	)
	(footprint ""
		(layer "F.Cu")
		(at 146.939 -121.793)
		(property "Reference" "R8088"
			(at 0 0 0)
			(layer "F.SilkS")
			(hide yes)
			(effects
				(font
					(size 1.27 1.27)
				)
			)
		)
		(property "Value" ""
			(at 0 0 0)
			(layer "F.Fab")
			(effects
				(font
					(size 1.27 1.27)
				)
			)
		)
		(duplicate_pad_numbers_are_jumpers no)
		(fp_line
			(start -0.7874 -0.4064)
			(end 0.7874 -0.4064)
			(stroke
				(width 0.1524)
				(type default)
			)
			(layer "F.SilkS")
		)
		(fp_line
			(start -0.7874 0.4064)
			(end -0.7874 -0.4064)
			(stroke
				(width 0.1524)
				(type default)
			)
			(layer "F.SilkS")
		)
		(fp_line
			(start 0.7874 -0.4064)
			(end 0.7874 0.4064)
			(stroke
				(width 0.1524)
				(type default)
			)
			(layer "F.SilkS")
		)
		(fp_line
			(start 0.7874 0.4064)
			(end -0.7874 0.4064)
			(stroke
				(width 0.1524)
				(type default)
			)
			(layer "F.SilkS")
		)
		(fp_line
			(start -0.67945 -0.305054)
			(end -0.12065 -0.305054)
			(stroke
				(width 0.1)
				(type default)
			)
			(layer "F.Fab")
		)
		(fp_line
			(start -0.67945 0.3048)
			(end -0.67945 -0.305054)
			(stroke
				(width 0.1)
				(type default)
			)
			(layer "F.Fab")
		)
		(fp_line
			(start -0.12065 -0.305054)
			(end -0.12065 -0.2794)
			(stroke
				(width 0.1)
				(type default)
			)
			(layer "F.Fab")
		)
		(fp_line
			(start -0.12065 -0.2794)
			(end 0.12065 -0.2794)
			(stroke
				(width 0.1)
				(type default)
			)
			(layer "F.Fab")
		)
		(fp_line
			(start -0.12065 0.2794)
			(end -0.12065 0.3048)
			(stroke
				(width 0.1)
				(type default)
			)
			(layer "F.Fab")
		)
		(fp_line
			(start -0.12065 0.3048)
			(end -0.67945 0.3048)
			(stroke
				(width 0.1)
				(type default)
			)
			(layer "F.Fab")
		)
		(fp_line
			(start 0.120396 0.2794)
			(end -0.12065 0.2794)
			(stroke
				(width 0.1)
				(type default)
			)
			(layer "F.Fab")
		)
		(fp_line
			(start 0.120396 0.3048)
			(end 0.120396 0.2794)
			(stroke
				(width 0.1)
				(type default)
			)
			(layer "F.Fab")
		)
		(fp_line
			(start 0.12065 -0.3048)
			(end 0.67945 -0.3048)
			(stroke
				(width 0.1)
				(type default)
			)
			(layer "F.Fab")
		)
		(fp_line
			(start 0.12065 -0.2794)
			(end 0.12065 -0.3048)
			(stroke
				(width 0.1)
				(type default)
			)
			(layer "F.Fab")
		)
		(fp_line
			(start 0.67945 -0.3048)
			(end 0.67945 0.3048)
			(stroke
				(width 0.1)
				(type default)
			)
			(layer "F.Fab")
		)
		(fp_line
			(start 0.67945 0.3048)
			(end 0.120396 0.3048)
			(stroke
				(width 0.1)
				(type default)
			)
			(layer "F.Fab")
		)
		(pad "1" smd circle
			(at -0.40005 0)
			(size 0 0)
			(layers "F.Cu" "F.Mask" "F.Paste")
			(net "P3V3_AUX")
		)
		(pad "2" smd circle
			(at 0.40005 0)
			(size 0 0)
			(layers "F.Cu" "F.Mask" "F.Paste")
			(net "PWRGD_CHAF_CPU1_R1")
		)
	)
)
